# S9S_MB_2U (Grand Teton) — schematic netlist excerpt (pin names and nets, part order shuffled) for the footprints in the layout excerpt that follows; sources: Cadence DE-HDL packaged netlist, KiCad conversion of 03242023_DA0F0TMBIJ0_F0T_Motherboard_J_brd_V01_OCP.brd

C1263  Q_CAP  10UF 6.3V 20% X6S  pkg C0402  page 189 : A = P1V8_PCH_PLL_AUX ; B = GND
R251  Q_RES  240 1% EMPTY  pkg 0402LF  page 120 : A = PVNN_TERM_CPU0 ; B = FM_S3M_CPU0_LVC1_GPIO_4

(kicad_pcb
	(version 20260206)
	(generator "pcbnew")
	(generator_version "10.0")
	(general
		(thickness 1.6)
		(legacy_teardrops no)
	)
	(paper "A4")
	(title_block
		(title "03242023_DA0F0TMBIJ0_F0T_Motherboard_J_brd_V01_OCP.brd")
		(comment 1 "Grand Teton / footprints 4457-4458 of 6105")
	)
	(layers
		(0 "F.Cu" signal "TOP")
		(4 "In1.Cu" signal "GND")
		(6 "In2.Cu" signal "IN1")
		(8 "In3.Cu" signal "GND1")
		(10 "In4.Cu" signal "IN2")
		(12 "In5.Cu" signal "GND2")
		(14 "In6.Cu" signal "IN3")
		(16 "In7.Cu" signal "GND3")
		(18 "In8.Cu" signal "VCC")
		(20 "In9.Cu" signal "VCC1")
		(22 "In10.Cu" signal "GND4")
		(24 "In11.Cu" signal "IN4")
		(26 "In12.Cu" signal "GND5")
		(28 "In13.Cu" signal "IN5")
		(30 "In14.Cu" signal "GND6")
		(32 "In15.Cu" signal "IN6")
		(34 "In16.Cu" signal "GND7")
		(2 "B.Cu" signal "BOTTOM")
		(9 "F.Adhes" user "F.Adhesive")
		(11 "B.Adhes" user "B.Adhesive")
		(13 "F.Paste" user "Package Geometry/Pastemask Top")
		(15 "B.Paste" user "Package Geometry/Pastemask Bottom")
		(5 "F.SilkS" user "Ref Des/Silkscreen Top")
		(7 "B.SilkS" user "Ref Des/Silkscreen Bottom")
		(1 "F.Mask" user "Board Geometry/Soldermask Top")
		(3 "B.Mask" user "Board Geometry/Soldermask Bottom")
		(17 "Dwgs.User" user "User.Drawings")
		(19 "Cmts.User" user "User.Comments")
		(21 "Eco1.User" user "User.Eco1")
		(23 "Eco2.User" user "User.Eco2")
		(25 "Edge.Cuts" user "Board Geometry/Outline")
		(27 "Margin" user)
		(31 "F.CrtYd" user "Package Geometry/Place Bound Top")
		(29 "B.CrtYd" user "Package Geometry/Place Bound Bottom")
		(35 "F.Fab" user "Ref Des/Assembly Top")
		(33 "B.Fab" user "Ref Des/Assembly Bottom")
	)
	(footprint ""
		(layer "B.Cu")
		(at 340.889844 -49.66462 180)
		(property "Reference" "C1263"
			(at 0 0 0)
			(layer "B.SilkS")
			(hide yes)
			(effects
				(font
					(size 1.27 1.27)
				)
				(justify mirror)
			)
		)
		(property "Value" ""
			(at 0 0 0)
			(layer "B.Fab")
			(effects
				(font
					(size 1.27 1.27)
				)
				(justify mirror)
			)
		)
		(duplicate_pad_numbers_are_jumpers no)
		(fp_line
			(start 0.7874 0.4064)
			(end 0.7874 -0.4064)
			(stroke
				(width 0.1524)
				(type default)
			)
			(layer "B.SilkS")
		)
		(fp_line
			(start 0.7874 -0.4064)
			(end -0.7874 -0.4064)
			(stroke
				(width 0.1524)
				(type default)
			)
			(layer "B.SilkS")
		)
		(fp_line
			(start -0.7874 0.4064)
			(end 0.7874 0.4064)
			(stroke
				(width 0.1524)
				(type default)
			)
			(layer "B.SilkS")
		)
		(fp_line
			(start -0.7874 -0.4064)
			(end -0.7874 0.4064)
			(stroke
				(width 0.1524)
				(type default)
			)
			(layer "B.SilkS")
		)
		(fp_line
			(start 0.67945 0.3048)
			(end 0.67945 -0.305054)
			(stroke
				(width 0.1)
				(type default)
			)
			(layer "B.Fab")
		)
		(fp_line
			(start 0.67945 -0.305054)
			(end 0.12065 -0.305054)
			(stroke
				(width 0.1)
				(type default)
			)
			(layer "B.Fab")
		)
		(fp_line
			(start 0.12065 0.3048)
			(end 0.67945 0.3048)
			(stroke
				(width 0.1)
				(type default)
			)
			(layer "B.Fab")
		)
		(fp_line
			(start 0.12065 0.2794)
			(end 0.12065 0.3048)
			(stroke
				(width 0.1)
				(type default)
			)
			(layer "B.Fab")
		)
		(fp_line
			(start 0.12065 -0.2794)
			(end -0.12065 -0.2794)
			(stroke
				(width 0.1)
				(type default)
			)
			(layer "B.Fab")
		)
		(fp_line
			(start 0.12065 -0.305054)
			(end 0.12065 -0.2794)
			(stroke
				(width 0.1)
				(type default)
			)
			(layer "B.Fab")
		)
		(fp_line
			(start -0.120396 0.3048)
			(end -0.120396 0.2794)
			(stroke
				(width 0.1)
				(type default)
			)
			(layer "B.Fab")
		)
		(fp_line
			(start -0.120396 0.2794)
			(end 0.12065 0.2794)
			(stroke
				(width 0.1)
				(type default)
			)
			(layer "B.Fab")
		)
		(fp_line
			(start -0.12065 -0.2794)
			(end -0.12065 -0.3048)
			(stroke
				(width 0.1)
				(type default)
			)
			(layer "B.Fab")
		)
		(fp_line
			(start -0.12065 -0.3048)
			(end -0.67945 -0.3048)
			(stroke
				(width 0.1)
				(type default)
			)
			(layer "B.Fab")
		)
		(fp_line
			(start -0.67945 0.3048)
			(end -0.120396 0.3048)
			(stroke
				(width 0.1)
				(type default)
			)
			(layer "B.Fab")
		)
		(fp_line
			(start -0.67945 -0.3048)
			(end -0.67945 0.3048)
			(stroke
				(width 0.1)
				(type default)
			)
			(layer "B.Fab")
		)
		(pad "1" smd circle
			(at 0.40005 0)
			(size 0 0)
			(layers "B.Cu" "B.Mask" "B.Paste")
			(net "P1V8_PCH_PLL_AUX")
		)
		(pad "2" smd circle
			(at -0.40005 0)
			(size 0 0)
			(layers "B.Cu" "B.Mask" "B.Paste")
			(net "GND")
		)
	)
	(footprint ""
		(layer "B.Cu")
		(at 276.147784 -193.669666 -90)
		(property "Reference" "R251"
			(at 0 0 90)
			(layer "B.SilkS")
			(hide yes)
			(effects
				(font
					(size 1.27 1.27)
				)
				(justify mirror)
			)
		)
		(property "Value" ""
			(at 0 0 90)
			(layer "B.Fab")
			(effects
				(font
					(size 1.27 1.27)
				)
				(justify mirror)
			)
		)
		(duplicate_pad_numbers_are_jumpers no)
		(fp_line
			(start -0.7874 0.4064)
			(end 0.7874 0.4064)
			(stroke
				(width 0.1524)
				(type default)
			)
			(layer "B.SilkS")
		)
		(fp_line
			(start 0.7874 0.4064)
			(end 0.7874 -0.4064)
			(stroke
				(width 0.1524)
				(type default)
			)
			(layer "B.SilkS")
		)
		(fp_line
			(start -0.7874 -0.4064)
			(end -0.7874 0.4064)
			(stroke
				(width 0.1524)
				(type default)
			)
			(layer "B.SilkS")
		)
		(fp_line
			(start 0.7874 -0.4064)
			(end -0.7874 -0.4064)
			(stroke
				(width 0.1524)
				(type default)
			)
			(layer "B.SilkS")
		)
		(fp_line
			(start -0.67945 0.3048)
			(end -0.120396 0.3048)
			(stroke
				(width 0.1)
				(type default)
			)
			(layer "B.Fab")
		)
		(fp_line
			(start -0.120396 0.3048)
			(end -0.120396 0.2794)
			(stroke
				(width 0.1)
				(type default)
			)
			(layer "B.Fab")
		)
		(fp_line
			(start 0.12065 0.3048)
			(end 0.67945 0.3048)
			(stroke
				(width 0.1)
				(type default)
			)
			(layer "B.Fab")
		)
		(fp_line
			(start 0.67945 0.3048)
			(end 0.67945 -0.305054)
			(stroke
				(width 0.1)
				(type default)
			)
			(layer "B.Fab")
		)
		(fp_line
			(start -0.120396 0.2794)
			(end 0.12065 0.2794)
			(stroke
				(width 0.1)
				(type default)
			)
			(layer "B.Fab")
		)
		(fp_line
			(start 0.12065 0.2794)
			(end 0.12065 0.3048)
			(stroke
				(width 0.1)
				(type default)
			)
			(layer "B.Fab")
		)
		(fp_line
			(start -0.12065 -0.2794)
			(end -0.12065 -0.3048)
			(stroke
				(width 0.1)
				(type default)
			)
			(layer "B.Fab")
		)
		(fp_line
			(start 0.12065 -0.2794)
			(end -0.12065 -0.2794)
			(stroke
				(width 0.1)
				(type default)
			)
			(layer "B.Fab")
		)
		(fp_line
			(start -0.67945 -0.3048)
			(end -0.67945 0.3048)
			(stroke
				(width 0.1)
				(type default)
			)
			(layer "B.Fab")
		)
		(fp_line
			(start -0.12065 -0.3048)
			(end -0.67945 -0.3048)
			(stroke
				(width 0.1)
				(type default)
			)
			(layer "B.Fab")
		)
		(fp_line
			(start 0.12065 -0.305054)
			(end 0.12065 -0.2794)
			(stroke
				(width 0.1)
				(type default)
			)
			(layer "B.Fab")
		)
		(fp_line
			(start 0.67945 -0.305054)
			(end 0.12065 -0.305054)
			(stroke
				(width 0.1)
				(type default)
			)
			(layer "B.Fab")
		)
		(pad "1" smd circle
			(at 0.40005 0 90)
			(size 0 0)
			(layers "B.Cu" "B.Mask" "B.Paste")
			(net "PVNN_TERM_CPU0")
		)
		(pad "2" smd circle
			(at -0.40005 0 90)
			(size 0 0)
			(layers "B.Cu" "B.Mask" "B.Paste")
			(net "FM_S3M_CPU0_LVC1_GPIO_4")
		)
	)
)
